(kicad_pcb
	(version 20260206)
	(generator "pcbnew")
	(generator_version "10.0")
	(general
		(thickness 1.6)
		(legacy_teardrops no)
	)
	(paper "A4")
	(title_block
		(title "v1-pdb — T6M_PDB_D_0927_0900.brd")
		(comment 1 "Open CloudServer (Microsoft) / footprint 239 of 321 (J26), pads 1-78 of 166")
	)
	(layers
		(0 "F.Cu" signal "TOP")
		(4 "In1.Cu" signal "GND")
		(6 "In2.Cu" signal "IN1")
		(8 "In3.Cu" signal "VCC")
		(10 "In4.Cu" signal "VCC1")
		(12 "In5.Cu" signal "IN2")
		(14 "In6.Cu" signal "GND1")
		(2 "B.Cu" signal "BOTTOM")
		(9 "F.Adhes" user "F.Adhesive")
		(11 "B.Adhes" user "B.Adhesive")
		(13 "F.Paste" user "Package Geometry/Pastemask Top")
		(15 "B.Paste" user "Package Geometry/Pastemask Bottom")
		(5 "F.SilkS" user "Ref Des/Silkscreen Top")
		(7 "B.SilkS" user "Ref Des/Silkscreen Bottom")
		(1 "F.Mask" user "Board Geometry/Soldermask Top")
		(3 "B.Mask" user "Board Geometry/Soldermask Bottom")
		(17 "Dwgs.User" user "User.Drawings")
		(19 "Cmts.User" user "User.Comments")
		(21 "Eco1.User" user "User.Eco1")
		(23 "Eco2.User" user "User.Eco2")
		(25 "Edge.Cuts" user "Board Geometry/Outline")
		(27 "Margin" user)
		(31 "F.CrtYd" user "Package Geometry/Place Bound Top")
		(29 "B.CrtYd" user "Package Geometry/Place Bound Bottom")
		(35 "F.Fab" user "Ref Des/Assembly Top")
		(33 "B.Fab" user "Ref Des/Assembly Bottom")
	)
	(footprint ""
		(layer "F.Cu")
		(at 6.448806 -261.670546)
		(property "Reference" "J26"
			(at 6.660642 8.995918 90)
			(unlocked yes)
			(layer "F.SilkS")
			(effects
				(font
					(size 0.7874 0.5842)
					(thickness 0.1524)
				)
				(justify left)
			)
		)
		(property "Value" ""
			(at 0 0 0)
			(layer "F.Fab")
			(effects
				(font
					(size 1.27 1.27)
				)
			)
		)
		(duplicate_pad_numbers_are_jumpers no)
		(pad "" np_thru_hole circle
			(at -1.249934 11.649964 270)
			(size 2.413 2.413)
			(drill 2.413)
			(layers "*.Cu" "*.Mask")
			(clearance 0.381)
			(thermal_gap 0.381)
		)
		(pad "" np_thru_hole circle
			(at -1.249934 84.799932 270)
			(size 2.413 2.413)
			(drill 2.413)
			(layers "*.Cu" "*.Mask")
			(clearance 0.381)
			(thermal_gap 0.381)
		)
		(pad "A1" thru_hole rect
			(at 0 0 270)
			(size 1.016 1.016)
			(drill 0.7112)
			(layers "*.Cu" "*.Mask")
			(remove_unused_layers no)
			(net "GND")
			(clearance 0.1016)
			(thermal_gap 0.1016)
			(padstack
				(mode front_inner_back)
				(layer "Inner"
					(shape circle)
					(size 1.016 1.016)
					(clearance 0.1016)
				)
				(layer "B.Cu"
					(shape rect)
					(size 1.016 1.016)
					(clearance 0.1016)
				)
			)
		)
		(pad "A2" thru_hole circle
			(at 1.999996 0.999998 270)
			(size 1.016 1.016)
			(drill 0.7112)
			(layers "*.Cu" "*.Mask")
			(remove_unused_layers no)
			(net "T5_BLAD3_EN")
			(clearance 0.1016)
			(thermal_gap 0.1016)
		)
		(pad "A3" thru_hole circle
			(at 0 1.999996 270)
			(size 1.016 1.016)
			(drill 0.7112)
			(layers "*.Cu" "*.Mask")
			(remove_unused_layers no)
			(net "T5_BLAD4_EN")
			(clearance 0.1016)
			(thermal_gap 0.1016)
		)
		(pad "A4" thru_hole circle
			(at 1.999996 2.999994 270)
			(size 1.016 1.016)
			(drill 0.7112)
			(layers "*.Cu" "*.Mask")
			(remove_unused_layers no)
			(net "GND")
			(clearance 0.1016)
			(thermal_gap 0.1016)
		)
		(pad "A5" thru_hole circle
			(at 0 3.999992 270)
			(size 1.016 1.016)
			(drill 0.7112)
			(layers "*.Cu" "*.Mask")
			(remove_unused_layers no)
			(net "T5_BLAD1_RXD")
			(clearance 0.1016)
			(thermal_gap 0.1016)
		)
		(pad "A6" thru_hole circle
			(at 1.999996 4.99999 270)
			(size 1.016 1.016)
			(drill 0.7112)
			(layers "*.Cu" "*.Mask")
			(remove_unused_layers no)
			(net "T5_BLAD1_TXD")
			(clearance 0.1016)
			(thermal_gap 0.1016)
		)
		(pad "A7" thru_hole circle
			(at 0 5.999988 270)
			(size 1.016 1.016)
			(drill 0.7112)
			(layers "*.Cu" "*.Mask")
			(remove_unused_layers no)
			(net "GND")
			(clearance 0.1016)
			(thermal_gap 0.1016)
		)
		(pad "A8" thru_hole circle
			(at 1.999996 6.999986 270)
			(size 1.016 1.016)
			(drill 0.7112)
			(layers "*.Cu" "*.Mask")
			(remove_unused_layers no)
			(net "T5_BLAD2_RXD")
			(clearance 0.1016)
			(thermal_gap 0.1016)
		)
		(pad "A9" thru_hole circle
			(at 0 7.999984 270)
			(size 1.016 1.016)
			(drill 0.7112)
			(layers "*.Cu" "*.Mask")
			(remove_unused_layers no)
			(net "T5_BLAD2_TXD")
			(clearance 0.1016)
			(thermal_gap 0.1016)
		)
		(pad "A10" thru_hole circle
			(at 1.999996 8.999982 270)
			(size 1.016 1.016)
			(drill 0.7112)
			(layers "*.Cu" "*.Mask")
			(remove_unused_layers no)
			(net "T5_BLAD3_RXD")
			(clearance 0.1016)
			(thermal_gap 0.1016)
		)
		(pad "A11" thru_hole circle
			(at 0 9.99998 270)
			(size 1.016 1.016)
			(drill 0.7112)
			(layers "*.Cu" "*.Mask")
			(remove_unused_layers no)
			(net "T5_BLAD3_TXD")
			(clearance 0.1016)
			(thermal_gap 0.1016)
		)
		(pad "A12" thru_hole circle
			(at 1.999996 12.999974 270)
			(size 1.016 1.016)
			(drill 0.7112)
			(layers "*.Cu" "*.Mask")
			(remove_unused_layers no)
			(net "T5_BLAD4_RXD")
			(clearance 0.1016)
			(thermal_gap 0.1016)
		)
		(pad "A13" thru_hole circle
			(at 0 13.999972 270)
			(size 1.016 1.016)
			(drill 0.7112)
			(layers "*.Cu" "*.Mask")
			(remove_unused_layers no)
			(net "T5_BLAD4_TXD")
			(clearance 0.1016)
			(thermal_gap 0.1016)
		)
		(pad "A14" thru_hole circle
			(at 1.999996 14.99997 270)
			(size 1.016 1.016)
			(drill 0.7112)
			(layers "*.Cu" "*.Mask")
			(remove_unused_layers no)
			(net "GND")
			(clearance 0.1016)
			(thermal_gap 0.1016)
		)
		(pad "A15" thru_hole circle
			(at 0 15.999968 270)
			(size 1.016 1.016)
			(drill 0.7112)
			(layers "*.Cu" "*.Mask")
			(remove_unused_layers no)
			(net "T3_BLAD1_EN")
			(clearance 0.1016)
			(thermal_gap 0.1016)
		)
		(pad "A16" thru_hole circle
			(at 1.999996 16.999966 270)
			(size 1.016 1.016)
			(drill 0.7112)
			(layers "*.Cu" "*.Mask")
			(remove_unused_layers no)
			(net "T3_BLAD2_EN")
			(clearance 0.1016)
			(thermal_gap 0.1016)
		)
		(pad "A17" thru_hole circle
			(at 0 17.999964 270)
			(size 1.016 1.016)
			(drill 0.7112)
			(layers "*.Cu" "*.Mask")
			(remove_unused_layers no)
			(net "T3_BLAD3_EN")
			(clearance 0.1016)
			(thermal_gap 0.1016)
		)
		(pad "A18" thru_hole circle
			(at 1.999996 18.999962 270)
			(size 1.016 1.016)
			(drill 0.7112)
			(layers "*.Cu" "*.Mask")
			(remove_unused_layers no)
			(net "T3_BLAD4_EN")
			(clearance 0.1016)
			(thermal_gap 0.1016)
		)
		(pad "A19" thru_hole circle
			(at 0 19.99996 270)
			(size 1.016 1.016)
			(drill 0.7112)
			(layers "*.Cu" "*.Mask")
			(remove_unused_layers no)
			(net "GND")
			(clearance 0.1016)
			(thermal_gap 0.1016)
		)
		(pad "A20" thru_hole circle
			(at 1.999996 20.999958 270)
			(size 1.016 1.016)
			(drill 0.7112)
			(layers "*.Cu" "*.Mask")
			(remove_unused_layers no)
			(net "T3_BLAD1_RXD")
			(clearance 0.1016)
			(thermal_gap 0.1016)
		)
		(pad "A21" thru_hole circle
			(at 0 21.999956 270)
			(size 1.016 1.016)
			(drill 0.7112)
			(layers "*.Cu" "*.Mask")
			(remove_unused_layers no)
			(net "T3_BLAD1_TXD")
			(clearance 0.1016)
			(thermal_gap 0.1016)
		)
		(pad "A22" thru_hole circle
			(at 1.999996 22.999954 270)
			(size 1.016 1.016)
			(drill 0.7112)
			(layers "*.Cu" "*.Mask")
			(remove_unused_layers no)
			(net "T3_BLAD2_RXD")
			(clearance 0.1016)
			(thermal_gap 0.1016)
		)
		(pad "A23" thru_hole circle
			(at 0 23.999952 270)
			(size 1.016 1.016)
			(drill 0.7112)
			(layers "*.Cu" "*.Mask")
			(remove_unused_layers no)
			(net "T3_BLAD2_TXD")
			(clearance 0.1016)
			(thermal_gap 0.1016)
		)
		(pad "A24" thru_hole circle
			(at 1.999996 24.99995 270)
			(size 1.016 1.016)
			(drill 0.7112)
			(layers "*.Cu" "*.Mask")
			(remove_unused_layers no)
			(net "GND")
			(clearance 0.1016)
			(thermal_gap 0.1016)
		)
		(pad "A25" thru_hole circle
			(at 0 25.999948 270)
			(size 1.016 1.016)
			(drill 0.7112)
			(layers "*.Cu" "*.Mask")
			(remove_unused_layers no)
			(net "T3_BLAD3_RXD")
			(clearance 0.1016)
			(thermal_gap 0.1016)
		)
		(pad "A26" thru_hole circle
			(at 1.999996 26.999946 270)
			(size 1.016 1.016)
			(drill 0.7112)
			(layers "*.Cu" "*.Mask")
			(remove_unused_layers no)
			(net "T3_BLAD3_TXD")
			(clearance 0.1016)
			(thermal_gap 0.1016)
		)
		(pad "A27" thru_hole circle
			(at 0 27.999944 270)
			(size 1.016 1.016)
			(drill 0.7112)
			(layers "*.Cu" "*.Mask")
			(remove_unused_layers no)
			(net "T3_BLAD4_RXD")
			(clearance 0.1016)
			(thermal_gap 0.1016)
		)
		(pad "A28" thru_hole circle
			(at 1.999996 28.999942 270)
			(size 1.016 1.016)
			(drill 0.7112)
			(layers "*.Cu" "*.Mask")
			(remove_unused_layers no)
			(net "T3_BLAD4_TXD")
			(clearance 0.1016)
			(thermal_gap 0.1016)
		)
		(pad "A29" thru_hole circle
			(at 0 29.99994 270)
			(size 1.016 1.016)
			(drill 0.7112)
			(layers "*.Cu" "*.Mask")
			(remove_unused_layers no)
			(net "GND")
			(clearance 0.1016)
			(thermal_gap 0.1016)
		)
		(pad "A30" thru_hole circle
			(at 1.999996 30.999938 270)
			(size 1.016 1.016)
			(drill 0.7112)
			(layers "*.Cu" "*.Mask")
			(remove_unused_layers no)
			(net "T1_BLAD1_EN")
			(clearance 0.1016)
			(thermal_gap 0.1016)
		)
		(pad "A31" thru_hole circle
			(at 0 31.999936 270)
			(size 1.016 1.016)
			(drill 0.7112)
			(layers "*.Cu" "*.Mask")
			(remove_unused_layers no)
			(net "T1_BLAD2_EN")
			(clearance 0.1016)
			(thermal_gap 0.1016)
		)
		(pad "A32" thru_hole circle
			(at 1.999996 32.999934 270)
			(size 1.016 1.016)
			(drill 0.7112)
			(layers "*.Cu" "*.Mask")
			(remove_unused_layers no)
			(net "T1_BLAD3_EN")
			(clearance 0.1016)
			(thermal_gap 0.1016)
		)
		(pad "A33" thru_hole circle
			(at 0 33.999932 270)
			(size 1.016 1.016)
			(drill 0.7112)
			(layers "*.Cu" "*.Mask")
			(remove_unused_layers no)
			(net "T1_BLAD4_EN")
			(clearance 0.1016)
			(thermal_gap 0.1016)
		)
		(pad "A34" thru_hole circle
			(at 1.999996 34.99993 270)
			(size 1.016 1.016)
			(drill 0.7112)
			(layers "*.Cu" "*.Mask")
			(remove_unused_layers no)
			(net "GND")
			(clearance 0.1016)
			(thermal_gap 0.1016)
		)
		(pad "A35" thru_hole circle
			(at 0 35.999928 270)
			(size 1.016 1.016)
			(drill 0.7112)
			(layers "*.Cu" "*.Mask")
			(remove_unused_layers no)
			(net "T1_BLAD2_RXD")
			(clearance 0.1016)
			(thermal_gap 0.1016)
		)
		(pad "A36" thru_hole circle
			(at 1.999996 36.999926 270)
			(size 1.016 1.016)
			(drill 0.7112)
			(layers "*.Cu" "*.Mask")
			(remove_unused_layers no)
			(net "T1_BLAD2_TXD")
			(clearance 0.1016)
			(thermal_gap 0.1016)
		)
		(pad "A37" thru_hole circle
			(at 0 37.999924 270)
			(size 1.016 1.016)
			(drill 0.7112)
			(layers "*.Cu" "*.Mask")
			(remove_unused_layers no)
			(net "T1_BLAD3_RXD")
			(clearance 0.1016)
			(thermal_gap 0.1016)
		)
		(pad "A38" thru_hole circle
			(at 1.999996 38.999922 270)
			(size 1.016 1.016)
			(drill 0.7112)
			(layers "*.Cu" "*.Mask")
			(remove_unused_layers no)
			(net "T1_BLAD3_TXD")
			(clearance 0.1016)
			(thermal_gap 0.1016)
		)
		(pad "A39" thru_hole circle
			(at 0 39.99992 270)
			(size 1.016 1.016)
			(drill 0.7112)
			(layers "*.Cu" "*.Mask")
			(remove_unused_layers no)
			(net "GND")
			(clearance 0.1016)
			(thermal_gap 0.1016)
		)
		(pad "A40" thru_hole circle
			(at 1.999996 40.999918 270)
			(size 1.016 1.016)
			(drill 0.7112)
			(layers "*.Cu" "*.Mask")
			(remove_unused_layers no)
			(net "T1_BLAD4_RXD")
			(clearance 0.1016)
			(thermal_gap 0.1016)
		)
		(pad "A41" thru_hole circle
			(at 0 41.999916 270)
			(size 1.016 1.016)
			(drill 0.7112)
			(layers "*.Cu" "*.Mask")
			(remove_unused_layers no)
			(net "T1_BLAD4_TXD")
			(clearance 0.1016)
			(thermal_gap 0.1016)
		)
		(pad "A42" thru_hole circle
			(at 1.999996 42.999914 270)
			(size 1.016 1.016)
			(drill 0.7112)
			(layers "*.Cu" "*.Mask")
			(remove_unused_layers no)
			(net "T1_BLAD1_RXD")
			(clearance 0.1016)
			(thermal_gap 0.1016)
		)
		(pad "A43" thru_hole circle
			(at 0 43.999912 270)
			(size 1.016 1.016)
			(drill 0.7112)
			(layers "*.Cu" "*.Mask")
			(remove_unused_layers no)
			(net "T1_BLAD1_TXD")
			(clearance 0.1016)
			(thermal_gap 0.1016)
		)
		(pad "A44" thru_hole circle
			(at 1.999996 44.99991 270)
			(size 1.016 1.016)
			(drill 0.7112)
			(layers "*.Cu" "*.Mask")
			(remove_unused_layers no)
			(net "GND")
			(clearance 0.1016)
			(thermal_gap 0.1016)
		)
		(pad "A45" thru_hole circle
			(at 0 45.999908 270)
			(size 1.016 1.016)
			(drill 0.7112)
			(layers "*.Cu" "*.Mask")
			(remove_unused_layers no)
			(net "PSU1_DC_OK")
			(clearance 0.1016)
			(thermal_gap 0.1016)
		)
		(pad "A46" thru_hole circle
			(at 1.999996 46.999906 270)
			(size 1.016 1.016)
			(drill 0.7112)
			(layers "*.Cu" "*.Mask")
			(remove_unused_layers no)
			(net "PSU2_DC_OK")
			(clearance 0.1016)
			(thermal_gap 0.1016)
		)
		(pad "A47" thru_hole circle
			(at 0 47.999904 270)
			(size 1.016 1.016)
			(drill 0.7112)
			(layers "*.Cu" "*.Mask")
			(remove_unused_layers no)
			(net "PSU3_DC_OK")
			(clearance 0.1016)
			(thermal_gap 0.1016)
		)
		(pad "A48" thru_hole circle
			(at 1.999996 48.999902 270)
			(size 1.016 1.016)
			(drill 0.7112)
			(layers "*.Cu" "*.Mask")
			(remove_unused_layers no)
			(net "PSU4_DC_OK")
			(clearance 0.1016)
			(thermal_gap 0.1016)
		)
		(pad "A49" thru_hole circle
			(at 0 49.9999 270)
			(size 1.016 1.016)
			(drill 0.7112)
			(layers "*.Cu" "*.Mask")
			(remove_unused_layers no)
			(net "PSU5_DC_OK")
			(clearance 0.1016)
			(thermal_gap 0.1016)
		)
		(pad "A50" thru_hole circle
			(at 1.999996 50.999898 270)
			(size 1.016 1.016)
			(drill 0.7112)
			(layers "*.Cu" "*.Mask")
			(remove_unused_layers no)
			(net "PSU6_DC_OK")
			(clearance 0.1016)
			(thermal_gap 0.1016)
		)
		(pad "A51" thru_hole circle
			(at 0 51.999896 270)
			(size 1.016 1.016)
			(drill 0.7112)
			(layers "*.Cu" "*.Mask")
			(remove_unused_layers no)
			(net "GND")
			(clearance 0.1016)
			(thermal_gap 0.1016)
		)
		(pad "A52" thru_hole circle
			(at 1.999996 52.999894 270)
			(size 1.016 1.016)
			(drill 0.7112)
			(layers "*.Cu" "*.Mask")
			(remove_unused_layers no)
			(net "UART_RTS_P6_L_N")
			(clearance 0.1016)
			(thermal_gap 0.1016)
		)
		(pad "A53" thru_hole circle
			(at 0 53.999892 270)
			(size 1.016 1.016)
			(drill 0.7112)
			(layers "*.Cu" "*.Mask")
			(remove_unused_layers no)
			(net "UART_DSR_P6_L_N")
			(clearance 0.1016)
			(thermal_gap 0.1016)
		)
		(pad "A54" thru_hole circle
			(at 1.999996 54.99989 270)
			(size 1.016 1.016)
			(drill 0.7112)
			(layers "*.Cu" "*.Mask")
			(remove_unused_layers no)
			(net "UART_RX_P6_L")
			(clearance 0.1016)
			(thermal_gap 0.1016)
		)
		(pad "A55" thru_hole circle
			(at 0 55.999888 270)
			(size 1.016 1.016)
			(drill 0.7112)
			(layers "*.Cu" "*.Mask")
			(remove_unused_layers no)
			(net "UART_TX_P6_L")
			(clearance 0.1016)
			(thermal_gap 0.1016)
		)
		(pad "A56" thru_hole circle
			(at 1.999996 56.999886 270)
			(size 1.016 1.016)
			(drill 0.7112)
			(layers "*.Cu" "*.Mask")
			(remove_unused_layers no)
			(net "UART_DTR_P6_L_N")
			(clearance 0.1016)
			(thermal_gap 0.1016)
		)
		(pad "A57" thru_hole circle
			(at 0 57.999884 270)
			(size 1.016 1.016)
			(drill 0.7112)
			(layers "*.Cu" "*.Mask")
			(remove_unused_layers no)
			(net "UART_CTS_P6_L_N")
			(clearance 0.1016)
			(thermal_gap 0.1016)
		)
		(pad "A58" thru_hole circle
			(at 1.999996 59.000136 270)
			(size 1.016 1.016)
			(drill 0.7112)
			(layers "*.Cu" "*.Mask")
			(remove_unused_layers no)
			(net "UART_RI_P6_L_N")
			(clearance 0.1016)
			(thermal_gap 0.1016)
		)
		(pad "A59" thru_hole circle
			(at 0 59.99988 270)
			(size 1.016 1.016)
			(drill 0.7112)
			(layers "*.Cu" "*.Mask")
			(remove_unused_layers no)
			(net "GND")
			(clearance 0.1016)
			(thermal_gap 0.1016)
		)
		(pad "A60" thru_hole circle
			(at 1.999996 61.000132 270)
			(size 1.016 1.016)
			(drill 0.7112)
			(layers "*.Cu" "*.Mask")
			(remove_unused_layers no)
			(net "UART_RTS_P2_L_N")
			(clearance 0.1016)
			(thermal_gap 0.1016)
		)
		(pad "A61" thru_hole circle
			(at 0 61.999876 270)
			(size 1.016 1.016)
			(drill 0.7112)
			(layers "*.Cu" "*.Mask")
			(remove_unused_layers no)
			(net "UART_DSR_P2_L_N")
			(clearance 0.1016)
			(thermal_gap 0.1016)
		)
		(pad "A62" thru_hole circle
			(at 1.999996 63.000128 270)
			(size 1.016 1.016)
			(drill 0.7112)
			(layers "*.Cu" "*.Mask")
			(remove_unused_layers no)
			(net "UART_RX_P2_L")
			(clearance 0.1016)
			(thermal_gap 0.1016)
		)
		(pad "A63" thru_hole circle
			(at 0 63.999872 270)
			(size 1.016 1.016)
			(drill 0.7112)
			(layers "*.Cu" "*.Mask")
			(remove_unused_layers no)
			(net "UART_TX_P2_L")
			(clearance 0.1016)
			(thermal_gap 0.1016)
		)
		(pad "A64" thru_hole circle
			(at 1.999996 65.000124 270)
			(size 1.016 1.016)
			(drill 0.7112)
			(layers "*.Cu" "*.Mask")
			(remove_unused_layers no)
			(net "UART_DTR_P2_L_N")
			(clearance 0.1016)
			(thermal_gap 0.1016)
		)
		(pad "A65" thru_hole circle
			(at 0 65.999868 270)
			(size 1.016 1.016)
			(drill 0.7112)
			(layers "*.Cu" "*.Mask")
			(remove_unused_layers no)
			(net "UART_CTS_P2_L_N")
			(clearance 0.1016)
			(thermal_gap 0.1016)
		)
		(pad "A66" thru_hole circle
			(at 1.999996 67.00012 270)
			(size 1.016 1.016)
			(drill 0.7112)
			(layers "*.Cu" "*.Mask")
			(remove_unused_layers no)
			(net "GND")
			(clearance 0.1016)
			(thermal_gap 0.1016)
		)
		(pad "A67" thru_hole circle
			(at 0 67.999864 270)
			(size 1.016 1.016)
			(drill 0.7112)
			(layers "*.Cu" "*.Mask")
			(remove_unused_layers no)
			(net "Net_409")
			(clearance 0.1016)
			(thermal_gap 0.1016)
		)
		(pad "A68" thru_hole circle
			(at 1.999996 69.000116 270)
			(size 1.016 1.016)
			(drill 0.7112)
			(layers "*.Cu" "*.Mask")
			(remove_unused_layers no)
			(net "Net_413")
			(clearance 0.1016)
			(thermal_gap 0.1016)
		)
		(pad "A69" thru_hole circle
			(at 0 70.000114 270)
			(size 1.016 1.016)
			(drill 0.7112)
			(layers "*.Cu" "*.Mask")
			(remove_unused_layers no)
			(net "Net_412")
			(clearance 0.1016)
			(thermal_gap 0.1016)
		)
		(pad "A70" thru_hole circle
			(at 1.999996 71.000112 270)
			(size 1.016 1.016)
			(drill 0.7112)
			(layers "*.Cu" "*.Mask")
			(remove_unused_layers no)
			(net "GND61")
			(clearance 0.1016)
			(thermal_gap 0.1016)
		)
		(pad "A71" thru_hole circle
			(at 0 72.00011 270)
			(size 1.016 1.016)
			(drill 0.7112)
			(layers "*.Cu" "*.Mask")
			(remove_unused_layers no)
			(net "GND")
			(clearance 0.1016)
			(thermal_gap 0.1016)
		)
		(pad "A72" thru_hole circle
			(at 1.999996 73.000108 270)
			(size 1.016 1.016)
			(drill 0.7112)
			(layers "*.Cu" "*.Mask")
			(remove_unused_layers no)
			(net "LAN1_P1_P")
			(clearance 0.1016)
			(thermal_gap 0.1016)
		)
		(pad "A73" thru_hole circle
			(at 0 74.000106 270)
			(size 1.016 1.016)
			(drill 0.7112)
			(layers "*.Cu" "*.Mask")
			(remove_unused_layers no)
			(net "LAN1_P1_N")
			(clearance 0.1016)
			(thermal_gap 0.1016)
		)
		(pad "A74" thru_hole circle
			(at 1.999996 75.000104 270)
			(size 1.016 1.016)
			(drill 0.7112)
			(layers "*.Cu" "*.Mask")
			(remove_unused_layers no)
			(net "GND")
			(clearance 0.1016)
			(thermal_gap 0.1016)
		)
		(pad "A75" thru_hole circle
			(at 0 76.000102 270)
			(size 1.016 1.016)
			(drill 0.7112)
			(layers "*.Cu" "*.Mask")
			(remove_unused_layers no)
			(net "LAN1_P2_P")
			(clearance 0.1016)
			(thermal_gap 0.1016)
		)
		(pad "A76" thru_hole circle
			(at 1.999996 77.0001 270)
			(size 1.016 1.016)
			(drill 0.7112)
			(layers "*.Cu" "*.Mask")
			(remove_unused_layers no)
			(net "LAN1_P2_N")
			(clearance 0.1016)
			(thermal_gap 0.1016)
		)
	)
)
